(kicad_pcb
	(version 20260206)
	(generator "pcbnew")
	(generator_version "10.0")
	(general
		(thickness 1.6)
		(legacy_teardrops no)
	)
	(paper "A4")
	(title_block
		(title "Wiwynn_Tioga_Pass_MB.brd")
		(comment 1 "Tioga Pass / footprints 4440-4446 of 4770")
	)
	(layers
		(0 "F.Cu" signal "TOP")
		(4 "In1.Cu" signal "L2GND")
		(6 "In2.Cu" signal "L3")
		(8 "In3.Cu" signal "L4GND")
		(10 "In4.Cu" signal "L5")
		(12 "In5.Cu" signal "L6GND")
		(14 "In6.Cu" signal "L7VCC")
		(16 "In7.Cu" signal "L8VCC")
		(18 "In8.Cu" signal "L9GND")
		(20 "In9.Cu" signal "L10")
		(22 "In10.Cu" signal "L11GND")
		(24 "In11.Cu" signal "L12")
		(26 "In12.Cu" signal "L13GND")
		(2 "B.Cu" signal "BOTTOM")
		(9 "F.Adhes" user "F.Adhesive")
		(11 "B.Adhes" user "B.Adhesive")
		(13 "F.Paste" user "Package Geometry/Pastemask Top")
		(15 "B.Paste" user "Package Geometry/Pastemask Bottom")
		(5 "F.SilkS" user "Ref Des/Silkscreen Top")
		(7 "B.SilkS" user "Ref Des/Silkscreen Bottom")
		(1 "F.Mask" user "Board Geometry/Soldermask Top")
		(3 "B.Mask" user "Board Geometry/Soldermask Bottom")
		(17 "Dwgs.User" user "User.Drawings")
		(19 "Cmts.User" user "User.Comments")
		(21 "Eco1.User" user "User.Eco1")
		(23 "Eco2.User" user "User.Eco2")
		(25 "Edge.Cuts" user "Board Geometry/Outline")
		(27 "Margin" user)
		(31 "F.CrtYd" user "Package Geometry/Place Bound Top")
		(29 "B.CrtYd" user "Package Geometry/Place Bound Bottom")
		(35 "F.Fab" user "Ref Des/Assembly Top")
		(33 "B.Fab" user "Ref Des/Assembly Bottom")
	)
	(footprint ""
		(layer "B.Cu")
		(at 197.848728 -74.506582 90)
		(property "Reference" "C6P19"
			(at 0 0 90)
			(layer "B.SilkS")
			(hide yes)
			(effects
				(font
					(size 1.27 1.27)
				)
				(justify mirror)
			)
		)
		(property "Value" ""
			(at 0 0 90)
			(layer "B.Fab")
			(effects
				(font
					(size 1.27 1.27)
				)
				(justify mirror)
			)
		)
		(duplicate_pad_numbers_are_jumpers no)
		(fp_rect
			(start 0.7239 1.9939)
			(end -0.7239 -0.2159)
			(stroke
				(width 0)
				(type default)
			)
			(fill no)
			(layer "B.CrtYd")
		)
		(fp_line
			(start 0.7239 -0.2159)
			(end 0.7239 1.9939)
			(stroke
				(width 0.1)
				(type default)
			)
			(layer "B.Fab")
		)
		(fp_line
			(start -0.7239 -0.2159)
			(end 0.7239 -0.2159)
			(stroke
				(width 0.1)
				(type default)
			)
			(layer "B.Fab")
		)
		(fp_line
			(start 0.7239 1.9939)
			(end -0.7239 1.9939)
			(stroke
				(width 0.1)
				(type default)
			)
			(layer "B.Fab")
		)
		(fp_line
			(start -0.7239 1.9939)
			(end -0.7239 -0.2159)
			(stroke
				(width 0.1)
				(type default)
			)
			(layer "B.Fab")
		)
		(pad "1" smd rect
			(at 0 0 270)
			(size 1.27 1.016)
			(layers "B.Cu" "B.Mask" "B.Paste")
			(net "VR_FET_SW_P12V_STBY_PVCCIN_CPU0")
		)
		(pad "2" smd rect
			(at 0 1.778 270)
			(size 1.27 1.016)
			(layers "B.Cu" "B.Mask" "B.Paste")
			(net "GND")
		)
		(zone
			(layer "B.Cu")
			(hatch none 0.5)
			(connect_pads
				(clearance 0)
			)
			(min_thickness 0.25)
			(keepout
				(tracks not_allowed)
				(vias allowed)
				(pads allowed)
				(copperpour not_allowed)
				(footprints allowed)
			)
			(placement
				(enabled no)
				(sheetname "")
			)
			(fill
				(thermal_gap 0.5)
				(thermal_bridge_width 0.5)
				(island_removal_mode 0)
			)
			(polygon
				(pts
					(xy 199.118728 -75.141582) (xy 198.356728 -75.141582) (xy 198.356728 -73.871582) (xy 199.118728 -73.871582)
				)
			)
		)
	)
	(footprint ""
		(layer "B.Cu")
		(at 489.189014 -153.924 90)
		(property "Reference" "U1L2"
			(at -2.633726 2.058416 270)
			(unlocked yes)
			(layer "B.SilkS")
			(effects
				(font
					(size 0.7874 0.5842)
					(thickness 0.1524)
				)
				(justify left mirror)
			)
		)
		(property "Value" ""
			(at 0 0 90)
			(layer "B.Fab")
			(effects
				(font
					(size 1.27 1.27)
				)
				(justify mirror)
			)
		)
		(duplicate_pad_numbers_are_jumpers no)
		(fp_circle
			(center 0.4699 -0.8382)
			(end 0.4699 -0.7112)
			(stroke
				(width 0.254)
				(type default)
			)
			(fill no)
			(layer "B.SilkS")
		)
		(fp_poly
			(pts
				(xy -0.21463 -0.450088) (xy -1.56337 -0.450088) (xy -1.56337 1.75006) (xy -0.21463 1.75006)
			)
			(stroke
				(width 0)
				(type default)
			)
			(fill no)
			(layer "B.CrtYd")
		)
		(fp_line
			(start -0.21463 -0.450088)
			(end -1.56337 -0.450088)
			(stroke
				(width 0.1)
				(type default)
			)
			(layer "B.Fab")
		)
		(fp_line
			(start -1.56337 -0.450088)
			(end -1.56337 1.75006)
			(stroke
				(width 0.1)
				(type default)
			)
			(layer "B.Fab")
		)
		(fp_line
			(start -0.21463 1.75006)
			(end -0.21463 -0.450088)
			(stroke
				(width 0.1)
				(type default)
			)
			(layer "B.Fab")
		)
		(fp_line
			(start -1.56337 1.75006)
			(end -0.21463 1.75006)
			(stroke
				(width 0.1)
				(type default)
			)
			(layer "B.Fab")
		)
		(fp_circle
			(center 0.4699 -0.8382)
			(end 0.4699 -0.7112)
			(stroke
				(width 0.254)
				(type default)
			)
			(fill no)
			(layer "B.Fab")
		)
		(pad "1" smd rect
			(at 0 0 270)
			(size 1.016 0.381)
			(layers "B.Cu" "B.Mask" "B.Paste")
			(net "PWRGD_P3V3_R")
		)
		(pad "2" smd rect
			(at 0 0.649986 270)
			(size 1.016 0.381)
			(layers "B.Cu" "B.Mask" "B.Paste")
			(net "FP_PWR_ID_LED_N")
		)
		(pad "3" smd rect
			(at 0 1.299972 270)
			(size 1.016 0.381)
			(layers "B.Cu" "B.Mask" "B.Paste")
			(net "GND")
		)
		(pad "4" smd rect
			(at -1.778 1.299972 270)
			(size 1.016 0.381)
			(layers "B.Cu" "B.Mask" "B.Paste")
			(net "FP_ID_LED_P5V_STBY_N")
		)
		(pad "5" smd rect
			(at -1.778 0 270)
			(size 1.016 0.381)
			(layers "B.Cu" "B.Mask" "B.Paste")
			(net "P5V_STBY")
		)
	)
	(footprint ""
		(layer "B.Cu")
		(at 80.731868 -140.208 -90)
		(property "Reference" "C5G114"
			(at -1.14681 0.76708 0)
			(unlocked yes)
			(layer "B.SilkS")
			(effects
				(font
					(size 0.7874 0.5842)
					(thickness 0.1524)
				)
				(justify mirror)
			)
		)
		(property "Value" ""
			(at 0 0 90)
			(layer "B.Fab")
			(effects
				(font
					(size 1.27 1.27)
				)
				(justify mirror)
			)
		)
		(duplicate_pad_numbers_are_jumpers no)
		(fp_rect
			(start 0.4953 1.6002)
			(end -0.4953 -0.2032)
			(stroke
				(width 0)
				(type default)
			)
			(fill no)
			(layer "B.CrtYd")
		)
		(fp_line
			(start -0.4953 1.6002)
			(end 0.4953 1.6002)
			(stroke
				(width 0.1)
				(type default)
			)
			(layer "B.Fab")
		)
		(fp_line
			(start 0.4953 1.6002)
			(end 0.4953 -0.2032)
			(stroke
				(width 0.1)
				(type default)
			)
			(layer "B.Fab")
		)
		(fp_line
			(start -0.4953 -0.2032)
			(end -0.4953 1.6002)
			(stroke
				(width 0.1)
				(type default)
			)
			(layer "B.Fab")
		)
		(fp_line
			(start 0.4953 -0.2032)
			(end -0.4953 -0.2032)
			(stroke
				(width 0.1)
				(type default)
			)
			(layer "B.Fab")
		)
		(pad "1" smd rect
			(at 0 0 90)
			(size 0.762 0.889)
			(layers "B.Cu" "B.Mask" "B.Paste")
			(net "PVDDQ_KLM")
		)
		(pad "2" smd rect
			(at 0 1.397 90)
			(size 0.762 0.889)
			(layers "B.Cu" "B.Mask" "B.Paste")
			(net "GND")
		)
		(zone
			(layer "B.Cu")
			(hatch none 0.5)
			(connect_pads
				(clearance 0)
			)
			(min_thickness 0.25)
			(keepout
				(tracks not_allowed)
				(vias allowed)
				(pads allowed)
				(copperpour not_allowed)
				(footprints allowed)
			)
			(placement
				(enabled no)
				(sheetname "")
			)
			(fill
				(thermal_gap 0.5)
				(thermal_bridge_width 0.5)
				(island_removal_mode 0)
			)
			(polygon
				(pts
					(xy 79.779368 -139.827) (xy 80.287368 -139.827) (xy 80.287368 -140.589) (xy 79.779368 -140.589)
				)
			)
		)
	)
	(footprint ""
		(layer "B.Cu")
		(at 422.2242 -83.1342 -90)
		(property "Reference" "R2P11"
			(at 0 0 90)
			(layer "B.SilkS")
			(hide yes)
			(effects
				(font
					(size 1.27 1.27)
				)
				(justify mirror)
			)
		)
		(property "Value" ""
			(at 0 0 90)
			(layer "B.Fab")
			(effects
				(font
					(size 1.27 1.27)
				)
				(justify mirror)
			)
		)
		(duplicate_pad_numbers_are_jumpers no)
		(fp_poly
			(pts
				(xy 0.2794 -0.1016) (xy -0.2794 -0.1016) (xy -0.2794 0.9906) (xy 0.2794 0.9906)
			)
			(stroke
				(width 0)
				(type default)
			)
			(fill no)
			(layer "B.CrtYd")
		)
		(fp_line
			(start -0.2794 0.9906)
			(end -0.2794 -0.1016)
			(stroke
				(width 0.1)
				(type default)
			)
			(layer "B.Fab")
		)
		(fp_line
			(start 0.2794 0.9906)
			(end -0.2794 0.9906)
			(stroke
				(width 0.1)
				(type default)
			)
			(layer "B.Fab")
		)
		(fp_line
			(start -0.2794 -0.1016)
			(end 0.2794 -0.1016)
			(stroke
				(width 0.1)
				(type default)
			)
			(layer "B.Fab")
		)
		(fp_line
			(start 0.2794 -0.1016)
			(end 0.2794 0.9906)
			(stroke
				(width 0.1)
				(type default)
			)
			(layer "B.Fab")
		)
		(pad "1" smd rect
			(at 0 0 90)
			(size 0.508 0.508)
			(layers "B.Cu" "B.Mask" "B.Paste")
			(net "FM_PMBUS_ALERT_BUF_EN_N")
		)
		(pad "2" smd rect
			(at 0 0.889 90)
			(size 0.508 0.508)
			(layers "B.Cu" "B.Mask" "B.Paste")
			(net "GND")
		)
		(zone
			(layer "B.Cu")
			(hatch none 0.5)
			(connect_pads
				(clearance 0)
			)
			(min_thickness 0.25)
			(keepout
				(tracks not_allowed)
				(vias allowed)
				(pads allowed)
				(copperpour not_allowed)
				(footprints allowed)
			)
			(placement
				(enabled no)
				(sheetname "")
			)
			(fill
				(thermal_gap 0.5)
				(thermal_bridge_width 0.5)
				(island_removal_mode 0)
			)
			(polygon
				(pts
					(xy 421.5892 -82.8802) (xy 421.5892 -83.3882) (xy 421.9702 -83.3882) (xy 421.9702 -82.8802)
				)
			)
		)
		(zone
			(layer "B.Cu")
			(hatch none 0.5)
			(connect_pads
				(clearance 0)
			)
			(min_thickness 0.25)
			(keepout
				(tracks allowed)
				(vias not_allowed)
				(pads allowed)
				(copperpour not_allowed)
				(footprints allowed)
			)
			(placement
				(enabled no)
				(sheetname "")
			)
			(fill
				(thermal_gap 0.5)
				(thermal_bridge_width 0.5)
				(island_removal_mode 0)
			)
			(polygon
				(pts
					(xy 421.9702 -82.8802) (xy 421.9702 -83.3882) (xy 421.5892 -83.3882) (xy 421.5892 -82.8802)
				)
			)
		)
	)
	(footprint ""
		(layer "B.Cu")
		(at 352.425 -108.4834)
		(property "Reference" "C3N40"
			(at 0 0 0)
			(layer "B.SilkS")
			(hide yes)
			(effects
				(font
					(size 1.27 1.27)
				)
				(justify mirror)
			)
		)
		(property "Value" ""
			(at 0 0 0)
			(layer "B.Fab")
			(effects
				(font
					(size 1.27 1.27)
				)
				(justify mirror)
			)
		)
		(duplicate_pad_numbers_are_jumpers no)
		(fp_poly
			(pts
				(xy -0.3048 -0.1016) (xy -0.3048 0.9906) (xy 0.3048 0.9906) (xy 0.3048 -0.1016)
			)
			(stroke
				(width 0)
				(type default)
			)
			(fill no)
			(layer "B.CrtYd")
		)
		(fp_line
			(start -0.3048 -0.1016)
			(end 0.3048 -0.1016)
			(stroke
				(width 0.1)
				(type default)
			)
			(layer "B.Fab")
		)
		(fp_line
			(start -0.3048 0.9906)
			(end -0.3048 -0.1016)
			(stroke
				(width 0.1)
				(type default)
			)
			(layer "B.Fab")
		)
		(fp_line
			(start 0.3048 -0.1016)
			(end 0.3048 0.9906)
			(stroke
				(width 0.1)
				(type default)
			)
			(layer "B.Fab")
		)
		(fp_line
			(start 0.3048 0.9906)
			(end -0.3048 0.9906)
			(stroke
				(width 0.1)
				(type default)
			)
			(layer "B.Fab")
		)
		(pad "1" smd rect
			(at 0 0 180)
			(size 0.508 0.508)
			(layers "B.Cu" "B.Mask" "B.Paste")
			(net "PVCCIOMCP_CPU0")
		)
		(pad "2" smd rect
			(at 0 0.889 180)
			(size 0.508 0.508)
			(layers "B.Cu" "B.Mask" "B.Paste")
			(net "GND")
		)
		(zone
			(layer "B.Cu")
			(hatch none 0.5)
			(connect_pads
				(clearance 0)
			)
			(min_thickness 0.25)
			(keepout
				(tracks allowed)
				(vias not_allowed)
				(pads allowed)
				(copperpour not_allowed)
				(footprints allowed)
			)
			(placement
				(enabled no)
				(sheetname "")
			)
			(fill
				(thermal_gap 0.5)
				(thermal_bridge_width 0.5)
				(island_removal_mode 0)
			)
			(polygon
				(pts
					(xy 352.679 -108.2294) (xy 352.171 -108.2294) (xy 352.171 -107.8484) (xy 352.679 -107.8484)
				)
			)
		)
		(zone
			(layer "B.Cu")
			(hatch none 0.5)
			(connect_pads
				(clearance 0)
			)
			(min_thickness 0.25)
			(keepout
				(tracks not_allowed)
				(vias allowed)
				(pads allowed)
				(copperpour not_allowed)
				(footprints allowed)
			)
			(placement
				(enabled no)
				(sheetname "")
			)
			(fill
				(thermal_gap 0.5)
				(thermal_bridge_width 0.5)
				(island_removal_mode 0)
			)
			(polygon
				(pts
					(xy 352.679 -107.8484) (xy 352.171 -107.8484) (xy 352.171 -108.2294) (xy 352.679 -108.2294)
				)
			)
		)
	)
	(footprint ""
		(layer "B.Cu")
		(at 470.027 -57.15 -90)
		(property "Reference" "R1R21"
			(at 0 0 90)
			(layer "B.SilkS")
			(hide yes)
			(effects
				(font
					(size 1.27 1.27)
				)
				(justify mirror)
			)
		)
		(property "Value" ""
			(at 0 0 90)
			(layer "B.Fab")
			(effects
				(font
					(size 1.27 1.27)
				)
				(justify mirror)
			)
		)
		(duplicate_pad_numbers_are_jumpers no)
		(fp_poly
			(pts
				(xy 0.2794 -0.1016) (xy -0.2794 -0.1016) (xy -0.2794 0.9906) (xy 0.2794 0.9906)
			)
			(stroke
				(width 0)
				(type default)
			)
			(fill no)
			(layer "B.CrtYd")
		)
		(fp_line
			(start -0.2794 0.9906)
			(end -0.2794 -0.1016)
			(stroke
				(width 0.1)
				(type default)
			)
			(layer "B.Fab")
		)
		(fp_line
			(start 0.2794 0.9906)
			(end -0.2794 0.9906)
			(stroke
				(width 0.1)
				(type default)
			)
			(layer "B.Fab")
		)
		(fp_line
			(start -0.2794 -0.1016)
			(end 0.2794 -0.1016)
			(stroke
				(width 0.1)
				(type default)
			)
			(layer "B.Fab")
		)
		(fp_line
			(start 0.2794 -0.1016)
			(end 0.2794 0.9906)
			(stroke
				(width 0.1)
				(type default)
			)
			(layer "B.Fab")
		)
		(pad "1" smd rect
			(at 0 0 90)
			(size 0.508 0.508)
			(layers "B.Cu" "B.Mask" "B.Paste")
			(net "P3V3_STBY")
		)
		(pad "2" smd rect
			(at 0 0.889 90)
			(size 0.508 0.508)
			(layers "B.Cu" "B.Mask" "B.Paste")
			(net "SMB_PCH_MEZZ_LOM1_SDA")
		)
		(zone
			(layer "B.Cu")
			(hatch none 0.5)
			(connect_pads
				(clearance 0)
			)
			(min_thickness 0.25)
			(keepout
				(tracks not_allowed)
				(vias allowed)
				(pads allowed)
				(copperpour not_allowed)
				(footprints allowed)
			)
			(placement
				(enabled no)
				(sheetname "")
			)
			(fill
				(thermal_gap 0.5)
				(thermal_bridge_width 0.5)
				(island_removal_mode 0)
			)
			(polygon
				(pts
					(xy 469.392 -56.896) (xy 469.392 -57.404) (xy 469.773 -57.404) (xy 469.773 -56.896)
				)
			)
		)
		(zone
			(layer "B.Cu")
			(hatch none 0.5)
			(connect_pads
				(clearance 0)
			)
			(min_thickness 0.25)
			(keepout
				(tracks allowed)
				(vias not_allowed)
				(pads allowed)
				(copperpour not_allowed)
				(footprints allowed)
			)
			(placement
				(enabled no)
				(sheetname "")
			)
			(fill
				(thermal_gap 0.5)
				(thermal_bridge_width 0.5)
				(island_removal_mode 0)
			)
			(polygon
				(pts
					(xy 469.773 -56.896) (xy 469.773 -57.404) (xy 469.392 -57.404) (xy 469.392 -56.896)
				)
			)
		)
	)
	(footprint ""
		(layer "B.Cu")
		(at 156.539692 -164.904674 -90)
		(property "Reference" "T1D23"
			(at 0 0 90)
			(layer "B.SilkS")
			(hide yes)
			(effects
				(font
					(size 1.27 1.27)
				)
				(justify mirror)
			)
		)
		(property "Value" "*"
			(at 3.4036 -4.46405 270)
			(unlocked yes)
			(layer "B.Fab")
			(hide yes)
			(effects
				(font
					(size 0.889 0.889)
					(thickness 0.1524)
				)
				(justify mirror)
			)
		)
		(property "Device Type" "TEST-PAD-12P-1-GP-U_DISCRET-GBA"
			(at 3.4036 -5.98805 270)
			(unlocked yes)
			(layer "B.Fab")
			(hide yes)
			(effects
				(font
					(size 0.889 0.889)
					(thickness 0.1524)
				)
				(justify mirror)
			)
		)
		(duplicate_pad_numbers_are_jumpers no)
		(fp_line
			(start -2.3622 3.4798)
			(end 2.3876 3.4798)
			(stroke
				(width 0.1524)
				(type default)
			)
			(layer "B.SilkS")
		)
		(fp_line
			(start 2.3876 3.4798)
			(end 2.3876 -4.826)
			(stroke
				(width 0.1524)
				(type default)
			)
			(layer "B.SilkS")
		)
		(fp_line
			(start -2.3622 -4.826)
			(end -2.3622 3.4798)
			(stroke
				(width 0.1524)
				(type default)
			)
			(layer "B.SilkS")
		)
		(fp_line
			(start 2.3876 -4.826)
			(end -2.3622 -4.826)
			(stroke
				(width 0.1524)
				(type default)
			)
			(layer "B.SilkS")
		)
		(fp_rect
			(start 2.6416 3.7338)
			(end -2.6162 -5.08)
			(stroke
				(width 0)
				(type default)
			)
			(fill no)
			(layer "B.CrtYd")
		)
		(fp_rect
			(start 2.6416 3.7338)
			(end -2.6162 -5.08)
			(stroke
				(width 0)
				(type default)
			)
			(fill no)
			(layer "B.Fab")
		)
		(pad "1" smd circle
			(at -0.496824 -1.301496 90)
			(size 0.6604 0.6604)
			(layers "B.Cu" "B.Mask" "B.Paste")
			(net "L14_85OHM_10INCH_DP")
		)
		(pad "2" smd circle
			(at 0.503936 -1.301496 90)
			(size 0.6604 0.6604)
			(layers "B.Cu" "B.Mask" "B.Paste")
			(net "L14_85OHM_10INCH_DN")
		)
		(pad "3" smd custom
			(at 0.00889 0.370078 90)
			(size 0.74295 0.74295)
			(layers "B.Cu" "B.Mask" "B.Paste")
			(net "GND")
			(options
				(clearance outline)
				(anchor circle)
			)
			(primitives
				(gr_poly
					(pts
						(xy -2.1209 -1.4859) (xy 2.1209 -1.4859) (xy 2.1209 1.4859) (xy 1.08585 1.4859) (xy 1.08585 0.4699)
						(xy -1.08585 0.4699) (xy -1.08585 1.4859) (xy -2.1209 1.4859)
					)
					(width 0)
					(fill yes)
				)
			)
		)
		(pad "4" thru_hole circle
			(at -1.266444 -3.851656 90)
			(size 1.4478 1.4478)
			(drill 1.0414)
			(layers "*.Cu" "*.Mask")
			(remove_unused_layers no)
			(net "GND")
			(clearance 0.1524)
			(thermal_gap 0.1524)
		)
		(pad "5" thru_hole circle
			(at 1.273556 -3.851656 90)
			(size 1.4478 1.4478)
			(drill 1.0414)
			(layers "*.Cu" "*.Mask")
			(remove_unused_layers no)
			(net "GND")
			(clearance 0.1524)
			(thermal_gap 0.1524)
		)
		(pad "6" thru_hole circle
			(at -1.266444 2.498344 90)
			(size 1.4478 1.4478)
			(drill 1.0414)
			(layers "*.Cu" "*.Mask")
			(remove_unused_layers no)
			(net "GND")
			(clearance 0.1524)
			(thermal_gap 0.1524)
		)
		(pad "7" thru_hole circle
			(at 1.273556 2.498344 90)
			(size 1.4478 1.4478)
			(drill 1.0414)
			(layers "*.Cu" "*.Mask")
			(remove_unused_layers no)
			(net "GND")
			(clearance 0.1524)
			(thermal_gap 0.1524)
		)
		(pad "8" thru_hole circle
			(at -1.27 -0.4572 90)
			(size 0.7112 0.7112)
			(drill 0.4064)
			(layers "*.Cu" "*.Mask")
			(remove_unused_layers no)
			(net "GND")
			(clearance 0.1016)
			(thermal_gap 0.1016)
		)
		(pad "9" thru_hole circle
			(at -1.27 0.762 90)
			(size 0.7112 0.7112)
			(drill 0.4064)
			(layers "*.Cu" "*.Mask")
			(remove_unused_layers no)
			(net "GND")
			(clearance 0.1016)
			(thermal_gap 0.1016)
		)
		(pad "10" thru_hole circle
			(at 0.0254 0.762 90)
			(size 0.7112 0.7112)
			(drill 0.4064)
			(layers "*.Cu" "*.Mask")
			(remove_unused_layers no)
			(net "GND")
			(clearance 0.1016)
			(thermal_gap 0.1016)
		)
		(pad "11" thru_hole circle
			(at 1.27 0.762 90)
			(size 0.7112 0.7112)
			(drill 0.4064)
			(layers "*.Cu" "*.Mask")
			(remove_unused_layers no)
			(net "GND")
			(clearance 0.1016)
			(thermal_gap 0.1016)
		)
		(pad "12" thru_hole circle
			(at 1.27 -0.4572 90)
			(size 0.7112 0.7112)
			(drill 0.4064)
			(layers "*.Cu" "*.Mask")
			(remove_unused_layers no)
			(net "GND")
			(clearance 0.1016)
			(thermal_gap 0.1016)
		)
	)
)
